(kicad_pcb
	(version 20260206)
	(generator "pcbnew")
	(generator_version "10.0")
	(general
		(thickness 1.6)
		(legacy_teardrops no)
	)
	(paper "A4")
	(title_block
		(title "Bryce Canyon_IOM_M2_16342-2_OCP.brd")
		(comment 1 "Bryce Canyon / footprints 118-123 of 1146")
	)
	(layers
		(0 "F.Cu" signal "TOP")
		(4 "In1.Cu" signal "L2GND")
		(6 "In2.Cu" signal "L3")
		(8 "In3.Cu" signal "L4VCC")
		(10 "In4.Cu" signal "L5VCC")
		(12 "In5.Cu" signal "L6")
		(14 "In6.Cu" signal "L7GND")
		(2 "B.Cu" signal "BOTTOM")
		(9 "F.Adhes" user "F.Adhesive")
		(11 "B.Adhes" user "B.Adhesive")
		(13 "F.Paste" user "Package Geometry/Pastemask Top")
		(15 "B.Paste" user "Package Geometry/Pastemask Bottom")
		(5 "F.SilkS" user "Ref Des/Silkscreen Top")
		(7 "B.SilkS" user "Ref Des/Silkscreen Bottom")
		(1 "F.Mask" user "Board Geometry/Soldermask Top")
		(3 "B.Mask" user "Board Geometry/Soldermask Bottom")
		(17 "Dwgs.User" user "User.Drawings")
		(19 "Cmts.User" user "User.Comments")
		(21 "Eco1.User" user "User.Eco1")
		(23 "Eco2.User" user "User.Eco2")
		(25 "Edge.Cuts" user "Board Geometry/Outline")
		(27 "Margin" user)
		(31 "F.CrtYd" user "Package Geometry/Place Bound Top")
		(29 "B.CrtYd" user "Package Geometry/Place Bound Bottom")
		(35 "F.Fab" user "Ref Des/Assembly Top")
		(33 "B.Fab" user "Ref Des/Assembly Bottom")
	)
	(footprint ""
		(layer "F.Cu")
		(at 134.897622 -8.034782 -90)
		(property "Reference" "Q5"
			(at 0 0 270)
			(layer "F.SilkS")
			(hide yes)
			(effects
				(font
					(size 1.27 1.27)
				)
			)
		)
		(property "Value" "PH0925CL-1-GP"
			(at -4.2799 -0.4572 270)
			(unlocked yes)
			(layer "F.Fab")
			(hide yes)
			(effects
				(font
					(size 1.016 1.016)
					(thickness 0.1524)
				)
			)
		)
		(property "Device Type" "LFPAK-5PH48-U"
			(at -4.2799 -1.9812 270)
			(unlocked yes)
			(layer "F.Fab")
			(hide yes)
			(effects
				(font
					(size 1.016 1.016)
					(thickness 0.1524)
				)
			)
		)
		(duplicate_pad_numbers_are_jumpers no)
		(fp_line
			(start -1.7272 1.1684)
			(end -2.1082 1.1684)
			(stroke
				(width 0.3302)
				(type default)
			)
			(layer "F.SilkS")
		)
		(fp_line
			(start -2.7559 1.0668)
			(end 2.7559 1.0668)
			(stroke
				(width 0.1524)
				(type default)
			)
			(layer "F.SilkS")
		)
		(fp_line
			(start 2.7559 1.0668)
			(end 2.7559 -6.5532)
			(stroke
				(width 0.1524)
				(type default)
			)
			(layer "F.SilkS")
		)
		(fp_line
			(start -2.7559 -6.5532)
			(end -2.7559 1.0668)
			(stroke
				(width 0.1524)
				(type default)
			)
			(layer "F.SilkS")
		)
		(fp_line
			(start 2.7559 -6.5532)
			(end -2.7559 -6.5532)
			(stroke
				(width 0.1524)
				(type default)
			)
			(layer "F.SilkS")
		)
		(fp_poly
			(pts
				(xy -2.34061 2.195322) (xy -1.90881 1.763522) (xy -1.47701 2.195322)
			)
			(stroke
				(width 0)
				(type default)
			)
			(fill yes)
			(layer "F.SilkS")
		)
		(fp_poly
			(pts
				(xy -2.5019 -1.09601) (xy -0.3302 -1.09601) (xy -0.3302 -3.36931) (xy -2.5019 -3.36931)
			)
			(stroke
				(width 0)
				(type default)
			)
			(fill yes)
			(layer "F.Paste")
		)
		(fp_poly
			(pts
				(xy 0.3302 -1.09601) (xy 2.5019 -1.09601) (xy 2.5019 -3.36931) (xy 0.3302 -3.36931)
			)
			(stroke
				(width 0)
				(type default)
			)
			(fill yes)
			(layer "F.Paste")
		)
		(fp_poly
			(pts
				(xy -2.5019 -4.02971) (xy -0.3302 -4.02971) (xy -0.3302 -6.30301) (xy -2.5019 -6.30301)
			)
			(stroke
				(width 0)
				(type default)
			)
			(fill yes)
			(layer "F.Paste")
		)
		(fp_poly
			(pts
				(xy 0.3302 -4.02971) (xy 2.5019 -4.02971) (xy 2.5019 -6.30301) (xy 0.3302 -6.30301)
			)
			(stroke
				(width 0)
				(type default)
			)
			(fill yes)
			(layer "F.Paste")
		)
		(fp_rect
			(start -2.4511 0.3048)
			(end 2.4511 -5.6896)
			(stroke
				(width 0)
				(type default)
			)
			(fill no)
			(layer "F.CrtYd")
		)
		(fp_poly
			(pts
				(xy -3.0099 1.3208) (xy -3.0099 -6.8072) (xy 3.0099 -6.8072) (xy 3.0099 -1.016) (xy 2.4511 -1.016)
				(xy 2.4511 -5.6896) (xy -2.4511 -5.6896) (xy -2.4511 0.3048) (xy 2.4511 0.3048) (xy 2.4511 -1.0033)
				(xy 3.0099 -1.0033) (xy 3.0099 1.3208)
			)
			(stroke
				(width 0)
				(type default)
			)
			(fill no)
			(layer "F.CrtYd")
		)
		(fp_rect
			(start -3.0099 1.3208)
			(end 3.0099 -6.8072)
			(stroke
				(width 0)
				(type default)
			)
			(fill no)
			(layer "F.Fab")
		)
		(pad "1" smd rect
			(at -1.905 0 270)
			(size 0.762 1.6256)
			(layers "F.Cu" "F.Mask" "F.Paste")
			(net "P12V_STBY")
		)
		(pad "2" smd rect
			(at -0.635 0 270)
			(size 0.762 1.6256)
			(layers "F.Cu" "F.Mask" "F.Paste")
			(net "P12V_STBY")
		)
		(pad "3" smd rect
			(at 0.635 0 270)
			(size 0.762 1.6256)
			(layers "F.Cu" "F.Mask" "F.Paste")
			(net "P12V_STBY")
		)
		(pad "4" smd rect
			(at 1.905 0 270)
			(size 0.762 1.6256)
			(layers "F.Cu" "F.Mask" "F.Paste")
			(net "MB0_12V_CTRL_GATE1")
		)
		(pad "5" smd rect
			(at 0 -3.69951 270)
			(size 5.0038 5.207)
			(layers "F.Cu" "F.Mask" "F.Paste")
			(net "MB0_P12V_MAIN_R")
		)
	)
	(footprint ""
		(layer "F.Cu")
		(at 63.126874 -175.139096)
		(property "Reference" "U9"
			(at 0 0 0)
			(layer "F.SilkS")
			(hide yes)
			(effects
				(font
					(size 1.27 1.27)
				)
			)
		)
		(property "Value" "SN74LVC1G07DCKRG4-2-GP"
			(at -2.3368 -8.6868 0)
			(unlocked yes)
			(layer "F.Fab")
			(hide yes)
			(effects
				(font
					(size 1.016 1.016)
					(thickness 0.1524)
				)
			)
		)
		(property "Device Type" "SC70-5H44"
			(at -2.3114 -10.414 0)
			(unlocked yes)
			(layer "F.Fab")
			(hide yes)
			(effects
				(font
					(size 1.016 1.016)
					(thickness 0.1524)
				)
			)
		)
		(duplicate_pad_numbers_are_jumpers no)
		(fp_line
			(start -1.27 -1.7018)
			(end 1.27 -1.7018)
			(stroke
				(width 0.1524)
				(type default)
			)
			(layer "F.SilkS")
		)
		(fp_line
			(start -1.27 1.7018)
			(end -1.27 -1.7018)
			(stroke
				(width 0.1524)
				(type default)
			)
			(layer "F.SilkS")
		)
		(fp_line
			(start 0.6604 -1.8034)
			(end 1.3843 -1.8034)
			(stroke
				(width 0.3302)
				(type default)
			)
			(layer "F.SilkS")
		)
		(fp_line
			(start 1.27 -1.7018)
			(end 1.27 1.7018)
			(stroke
				(width 0.1524)
				(type default)
			)
			(layer "F.SilkS")
		)
		(fp_line
			(start 1.27 1.7018)
			(end -1.27 1.7018)
			(stroke
				(width 0.1524)
				(type default)
			)
			(layer "F.SilkS")
		)
		(fp_line
			(start 1.3843 -1.8034)
			(end 1.3843 -1.1176)
			(stroke
				(width 0.3302)
				(type default)
			)
			(layer "F.SilkS")
		)
		(fp_rect
			(start -1.524 1.9558)
			(end 1.524 -1.9558)
			(stroke
				(width 0)
				(type default)
			)
			(fill no)
			(layer "F.CrtYd")
		)
		(fp_poly
			(pts
				(xy -1.524 -1.9558) (xy 1.524 -1.9558) (xy 1.524 1.9558) (xy -1.524 1.9558)
			)
			(stroke
				(width 0)
				(type default)
			)
			(fill no)
			(layer "F.Fab")
		)
		(pad "1" smd rect
			(at 0.65024 -0.8255)
			(size 0.4064 1.2192)
			(layers "F.Cu" "F.Mask" "F.Paste")
			(net "Net_526")
		)
		(pad "2" smd rect
			(at 0 -0.8255)
			(size 0.4064 1.2192)
			(layers "F.Cu" "F.Mask" "F.Paste")
			(net "FM_BMC_RESET_N")
		)
		(pad "3" smd rect
			(at -0.65024 -0.8255)
			(size 0.4064 1.2192)
			(layers "F.Cu" "F.Mask" "F.Paste")
			(net "GND")
		)
		(pad "4" smd rect
			(at -0.65024 0.8255)
			(size 0.4064 1.2192)
			(layers "F.Cu" "F.Mask" "F.Paste")
			(net "FM_TPM_PRSNT_RST_N_C")
		)
		(pad "5" smd rect
			(at 0.65024 0.8255)
			(size 0.4064 1.2192)
			(layers "F.Cu" "F.Mask" "F.Paste")
			(net "P3V3_STBY")
		)
	)
	(footprint ""
		(layer "F.Cu")
		(at 52.8574 -130.8608)
		(property "Reference" "TP12"
			(at 0 0 0)
			(layer "F.SilkS")
			(hide yes)
			(effects
				(font
					(size 1.27 1.27)
				)
			)
		)
		(property "Value" "TPAD28-2-GP"
			(at -0.0127 -1.6637 0)
			(unlocked yes)
			(layer "F.Fab")
			(hide yes)
			(effects
				(font
					(size 1.016 1.016)
					(thickness 0.1524)
				)
			)
		)
		(property "Device Type" "TPAD28"
			(at -0.0127 -3.1877 0)
			(unlocked yes)
			(layer "F.Fab")
			(hide yes)
			(effects
				(font
					(size 1.016 1.016)
					(thickness 0.1524)
				)
			)
		)
		(duplicate_pad_numbers_are_jumpers no)
		(fp_poly
			(pts
				(arc
					(start 0.3556 0)
					(mid -0.3556 0)
					(end 0.3556 0)
				)
			)
			(stroke
				(width 0)
				(type default)
			)
			(fill no)
			(layer "F.CrtYd")
		)
		(fp_poly
			(pts
				(arc
					(start 0.6096 0)
					(mid -0.6096 0)
					(end 0.6096 0)
				)
			)
			(stroke
				(width 0)
				(type default)
			)
			(fill no)
			(layer "F.Fab")
		)
		(pad "1" smd circle
			(at 0 0)
			(size 0.7112 0.7112)
			(layers "F.Cu" "F.Mask" "F.Paste")
			(net "TP_BMC0_LPC_LAD3")
		)
	)
	(footprint ""
		(layer "F.Cu")
		(at 213.910672 -47.476156 180)
		(property "Reference" "R478"
			(at 0 0 180)
			(layer "F.SilkS")
			(hide yes)
			(effects
				(font
					(size 1.27 1.27)
				)
			)
		)
		(property "Value" "10KR2F-2-GP"
			(at 0.064008 -3.993896 180)
			(unlocked yes)
			(layer "F.Fab")
			(hide yes)
			(effects
				(font
					(size 1.016 1.016)
					(thickness 0.1524)
				)
			)
		)
		(property "Device Type" "R402H16"
			(at 0.064008 -5.517896 180)
			(unlocked yes)
			(layer "F.Fab")
			(hide yes)
			(effects
				(font
					(size 1.016 1.016)
					(thickness 0.1524)
				)
			)
		)
		(duplicate_pad_numbers_are_jumpers no)
		(fp_line
			(start 0.508 -0.9398)
			(end -0.508 -0.9398)
			(stroke
				(width 0.1524)
				(type default)
			)
			(layer "F.SilkS")
		)
		(fp_line
			(start -0.508 -0.9398)
			(end -0.508 0.9398)
			(stroke
				(width 0.1524)
				(type default)
			)
			(layer "F.SilkS")
		)
		(fp_rect
			(start -0.508 0.9398)
			(end 0.508 -0.9398)
			(stroke
				(width 0)
				(type default)
			)
			(fill no)
			(layer "F.CrtYd")
		)
		(fp_rect
			(start -0.508 0.9398)
			(end 0.508 -0.9398)
			(stroke
				(width 0)
				(type default)
			)
			(fill no)
			(layer "F.Fab")
		)
		(pad "1" smd custom
			(at 0 -0.4445 180)
			(size 0.1397 0.1397)
			(layers "F.Cu" "F.Mask" "F.Paste")
			(net "P5V_VFB")
			(options
				(clearance outline)
				(anchor circle)
			)
			(primitives
				(gr_poly
					(pts
						(arc
							(start -0.1778 -0.2794)
							(mid -0.249642 -0.249642)
							(end -0.2794 -0.1778)
						)
						(arc
							(start -0.2794 0.1778)
							(mid -0.249642 0.249642)
							(end -0.1778 0.2794)
						)
						(arc
							(start 0.1778 0.2794)
							(mid 0.249642 0.249642)
							(end 0.2794 0.1778)
						)
						(arc
							(start 0.2794 -0.1778)
							(mid 0.249642 -0.249642)
							(end 0.1778 -0.2794)
						)
					)
					(width 0)
					(fill yes)
				)
			)
		)
		(pad "2" smd custom
			(at 0 0.4445 180)
			(size 0.1397 0.1397)
			(layers "F.Cu" "F.Mask" "F.Paste")
			(net "AGND_P5V")
			(options
				(clearance outline)
				(anchor circle)
			)
			(primitives
				(gr_poly
					(pts
						(arc
							(start -0.1778 -0.2794)
							(mid -0.249642 -0.249642)
							(end -0.2794 -0.1778)
						)
						(arc
							(start -0.2794 0.1778)
							(mid -0.249642 0.249642)
							(end -0.1778 0.2794)
						)
						(arc
							(start 0.1778 0.2794)
							(mid 0.249642 0.249642)
							(end 0.2794 0.1778)
						)
						(arc
							(start 0.2794 -0.1778)
							(mid 0.249642 -0.249642)
							(end 0.1778 -0.2794)
						)
					)
					(width 0)
					(fill yes)
				)
			)
		)
	)
	(footprint ""
		(layer "F.Cu")
		(at 79.93888 -172.72508)
		(property "Reference" "C195"
			(at 0 0 0)
			(layer "F.SilkS")
			(hide yes)
			(effects
				(font
					(size 1.27 1.27)
				)
			)
		)
		(property "Value" "SCD1U16V2KX-3GP"
			(at 1.1811 -2.7051 0)
			(unlocked yes)
			(layer "F.Fab")
			(hide yes)
			(effects
				(font
					(size 1.016 1.016)
					(thickness 0.1524)
				)
			)
		)
		(property "Device Type" "C402H22"
			(at 1.1811 -4.2291 0)
			(unlocked yes)
			(layer "F.Fab")
			(hide yes)
			(effects
				(font
					(size 1.016 1.016)
					(thickness 0.1524)
				)
			)
		)
		(duplicate_pad_numbers_are_jumpers no)
		(fp_rect
			(start -0.4318 0.9525)
			(end 0.4318 -0.9525)
			(stroke
				(width 0)
				(type default)
			)
			(fill no)
			(layer "F.CrtYd")
		)
		(fp_rect
			(start -0.4318 0.9525)
			(end 0.4318 -0.9525)
			(stroke
				(width 0)
				(type default)
			)
			(fill no)
			(layer "F.Fab")
		)
		(pad "1" smd custom
			(at 0 -0.4445)
			(size 0.1524 0.1524)
			(layers "F.Cu" "F.Mask" "F.Paste")
			(net "TPS74801_P2V5_STBY_OUT")
			(options
				(clearance outline)
				(anchor circle)
			)
			(primitives
				(gr_poly
					(pts
						(arc
							(start 0.3048 -0.2032)
							(mid 0.275042 -0.275042)
							(end 0.2032 -0.3048)
						)
						(arc
							(start -0.2032 -0.3048)
							(mid -0.275042 -0.275042)
							(end -0.3048 -0.2032)
						)
						(arc
							(start -0.3048 0.2032)
							(mid -0.275042 0.275042)
							(end -0.2032 0.3048)
						)
						(arc
							(start 0.2032 0.3048)
							(mid 0.275042 0.275042)
							(end 0.3048 0.2032)
						)
					)
					(width 0)
					(fill yes)
				)
			)
		)
		(pad "2" smd custom
			(at 0 0.4445)
			(size 0.1524 0.1524)
			(layers "F.Cu" "F.Mask" "F.Paste")
			(net "GND")
			(options
				(clearance outline)
				(anchor circle)
			)
			(primitives
				(gr_poly
					(pts
						(arc
							(start 0.3048 -0.2032)
							(mid 0.275042 -0.275042)
							(end 0.2032 -0.3048)
						)
						(arc
							(start -0.2032 -0.3048)
							(mid -0.275042 -0.275042)
							(end -0.3048 -0.2032)
						)
						(arc
							(start -0.3048 0.2032)
							(mid -0.275042 0.275042)
							(end -0.2032 0.3048)
						)
						(arc
							(start 0.2032 0.3048)
							(mid 0.275042 0.275042)
							(end 0.3048 0.2032)
						)
					)
					(width 0)
					(fill yes)
				)
			)
		)
	)
	(footprint ""
		(layer "F.Cu")
		(at 224.968054 -77.141832 90)
		(property "Reference" "C657"
			(at 0 0 90)
			(layer "F.SilkS")
			(hide yes)
			(effects
				(font
					(size 1.27 1.27)
				)
			)
		)
		(property "Value" "ST100U6D3VDM-8-GP"
			(at 0 -9.6012 90)
			(unlocked yes)
			(layer "F.Fab")
			(hide yes)
			(effects
				(font
					(size 1.016 1.016)
					(thickness 0.1524)
				)
			)
		)
		(property "Device Type" "CT7343H83"
			(at 0 -11.1252 90)
			(unlocked yes)
			(layer "F.Fab")
			(hide yes)
			(effects
				(font
					(size 1.016 1.016)
					(thickness 0.1524)
				)
			)
		)
		(duplicate_pad_numbers_are_jumpers no)
		(fp_line
			(start 2.286 -4.8768)
			(end -2.286 -4.8768)
			(stroke
				(width 0.1524)
				(type default)
			)
			(layer "F.SilkS")
		)
		(fp_line
			(start -2.286 -4.8768)
			(end -2.286 -2.032)
			(stroke
				(width 0.1524)
				(type default)
			)
			(layer "F.SilkS")
		)
		(fp_line
			(start 2.1082 -4.699)
			(end -2.1082 -4.699)
			(stroke
				(width 0.508)
				(type default)
			)
			(layer "F.SilkS")
		)
		(fp_line
			(start 2.286 -2.032)
			(end 2.286 -4.8768)
			(stroke
				(width 0.1524)
				(type default)
			)
			(layer "F.SilkS")
		)
		(fp_line
			(start 2.286 2.032)
			(end 2.286 4.8768)
			(stroke
				(width 0.1524)
				(type default)
			)
			(layer "F.SilkS")
		)
		(fp_line
			(start 2.286 4.8768)
			(end -2.286 4.8768)
			(stroke
				(width 0.1524)
				(type default)
			)
			(layer "F.SilkS")
		)
		(fp_line
			(start -2.286 4.8768)
			(end -2.286 2.032)
			(stroke
				(width 0.1524)
				(type default)
			)
			(layer "F.SilkS")
		)
		(fp_rect
			(start -2.1463 3.6449)
			(end 2.1463 -3.6449)
			(stroke
				(width 0)
				(type default)
			)
			(fill no)
			(layer "F.CrtYd")
		)
		(fp_poly
			(pts
				(xy -2.54 4.953) (xy -2.54 4.2926) (xy -3.81 4.2926) (xy -3.81 -4.2926) (xy -2.54 -4.2926) (xy -2.54 -4.953)
				(xy 2.54 -4.953) (xy 2.54 -4.2926) (xy 3.81 -4.2926) (xy 3.81 -1.6256) (xy 2.1463 -1.6256) (xy 2.1463 -3.6449)
				(xy -2.1463 -3.6449) (xy -2.1463 3.6449) (xy 2.1463 3.6449) (xy 2.1463 -1.6129) (xy 3.81 -1.6129)
				(xy 3.81 4.2926) (xy 2.54 4.2926) (xy 2.54 4.953)
			)
			(stroke
				(width 0)
				(type default)
			)
			(fill no)
			(layer "F.CrtYd")
		)
		(fp_rect
			(start 2.54 4.2926)
			(end 3.81 -4.2926)
			(stroke
				(width 0)
				(type default)
			)
			(fill no)
			(layer "F.Fab")
		)
		(fp_rect
			(start -3.81 4.2926)
			(end -2.54 -4.2926)
			(stroke
				(width 0)
				(type default)
			)
			(fill no)
			(layer "F.Fab")
		)
		(fp_rect
			(start -2.54 4.953)
			(end 2.54 -4.953)
			(stroke
				(width 0)
				(type default)
			)
			(fill no)
			(layer "F.Fab")
		)
		(pad "1" smd rect
			(at 0 -3.1496 90)
			(size 2.413 2.286)
			(layers "F.Cu" "F.Mask" "F.Paste")
			(net "P3V3_M2")
		)
		(pad "2" smd rect
			(at 0 3.1496 90)
			(size 2.413 2.286)
			(layers "F.Cu" "F.Mask" "F.Paste")
			(net "GND")
		)
		(zone
			(layer "F.Cu")
			(hatch none 0.5)
			(connect_pads
				(clearance 0)
			)
			(min_thickness 0.25)
			(keepout
				(tracks allowed)
				(vias not_allowed)
				(pads allowed)
				(copperpour not_allowed)
				(footprints allowed)
			)
			(placement
				(enabled no)
				(sheetname "")
			)
			(fill
				(thermal_gap 0.5)
				(thermal_bridge_width 0.5)
				(island_removal_mode 0)
			)
			(polygon
				(pts
					(xy 223.278954 -78.653132) (xy 220.370654 -78.653132) (xy 220.370654 -75.630532) (xy 223.266254 -75.630532)
					(xy 223.596454 -75.630532) (xy 223.596454 -78.653132)
				)
			)
		)
		(zone
			(layer "F.Cu")
			(hatch none 0.5)
			(connect_pads
				(clearance 0)
			)
			(min_thickness 0.25)
			(keepout
				(tracks allowed)
				(vias not_allowed)
				(pads allowed)
				(copperpour not_allowed)
				(footprints allowed)
			)
			(placement
				(enabled no)
				(sheetname "")
			)
			(fill
				(thermal_gap 0.5)
				(thermal_bridge_width 0.5)
				(island_removal_mode 0)
			)
			(polygon
				(pts
					(xy 229.565454 -75.630532) (xy 229.565454 -78.653132) (xy 226.669854 -78.653132) (xy 226.339654 -78.653132)
					(xy 226.339654 -75.630532) (xy 226.669854 -75.630532)
				)
			)
		)
	)
)
